G04 ================== begin FILE IDENTIFICATION RECORD ==================*
G04 Layout Name:  17301-sa.brd*
G04 Film Name:    L2GND*
G04 File Format:  Gerber RS274X*
G04 File Origin:  Cadence Allegro 16.6-2015-S079*
G04 Origin Date:  Thu Jun 22 17:50:01 2017*
G04 *
G04 Layer:  VIA CLASS/L2GND*
G04 Layer:  PIN/L2GND*
G04 Layer:  ETCH/L2GND*
G04 Layer:  DRAWING FORMAT/LAYER_PCB_STORY*
G04 Layer:  DRAWING FORMAT/LAYER_L2GND*
G04 *
G04 Offset:    (0.00 0.00)*
G04 Mirror:    No*
G04 Mode:      Negative*
G04 Rotation:  0*
G04 FullContactRelief:  No*
G04 UndefLineWidth:     6.00*
G04 ================== end FILE IDENTIFICATION RECORD ====================*
%FSLAX35Y35*MOIN*%
%IR0*IPPOS*OFA0.00000B0.00000*MIA0B0*SFA1.00000B1.00000*%
%AMMACRO26*
4,1,15,-.03299,.01885,
-.035762,.012835,
-.037448,.00643,
-.037995,-.00017,
-.037388,-.006766,
-.035646,-.013155,
-.03299,-.01885,
-.03664,-.0225,
-.03999,-.015796,
-.042126,-.008611,
-.042981,-.001166,
-.042531,.006316,
-.040788,.013605,
-.037806,.020481,
-.03664,.0225,
-.03299,.01885,
0.0*
4,1,15,-.01885,-.03299,
-.012835,-.035762,
-.00643,-.037448,
.00017,-.037995,
.006766,-.037388,
.013155,-.035646,
.01885,-.03299,
.0225,-.03664,
.015796,-.03999,
.008611,-.042126,
.001166,-.042981,
-.006316,-.042531,
-.013605,-.040788,
-.020481,-.037806,
-.0225,-.03664,
-.01885,-.03299,
0.0*
4,1,15,.03299,-.01885,
.035762,-.012835,
.037448,-.00643,
.037995,.00017,
.037388,.006766,
.035646,.013155,
.03299,.01885,
.03664,.0225,
.03999,.015796,
.042126,.008611,
.042981,.001166,
.042531,-.006316,
.040788,-.013605,
.037806,-.020481,
.03664,-.0225,
.03299,-.01885,
0.0*
4,1,15,.01885,.03299,
.012835,.035762,
.00643,.037448,
-.00017,.037995,
-.006766,.037388,
-.013155,.035646,
-.01885,.03299,
-.0225,.03664,
-.015796,.03999,
-.008611,.042126,
-.001166,.042981,
.006316,.042531,
.013605,.040788,
.020481,.037806,
.0225,.03664,
.01885,.03299,
0.0*
%
%ADD26MACRO26*%
%ADD16C,.03*%
%ADD15C,.032*%
%ADD19C,.044*%
%ADD20C,.081*%
%ADD17C,.048*%
%ADD22C,.076*%
%ADD25C,.086*%
%ADD24C,.078*%
%AMMACRO13*
4,1,19,.00048,.00013,
.000487,.000102,
.000492,.000073,
.000495,.000045,
.000497,.000016,
.000497,-.000013,
.000496,-.000042,
.000492,-.000071,
.000487,-.000099,
.000481,-.000127,
.00048,-.00013,
.00086,-.00051,
.000935,-.000353,
.000983,-.000185,
.001,-.000012,
.000987,.000162,
.000943,.000331,
.000872,.00049,
.00086,.00051,
.00048,.00013,
0.0*
4,1,19,.00013,-.00048,
.000102,-.000487,
.000073,-.000492,
.000045,-.000495,
.000016,-.000497,
-.000013,-.000497,
-.000042,-.000496,
-.000071,-.000492,
-.000099,-.000487,
-.000127,-.000481,
-.00013,-.00048,
-.00051,-.00086,
-.000353,-.000935,
-.000185,-.000983,
-.000012,-.001,
.000162,-.000987,
.000331,-.000943,
.00049,-.000872,
.00051,-.00086,
.00013,-.00048,
0.0*
4,1,19,-.00048,-.00013,
-.000487,-.000102,
-.000492,-.000073,
-.000495,-.000045,
-.000497,-.000016,
-.000497,.000013,
-.000496,.000042,
-.000492,.000071,
-.000487,.000099,
-.000481,.000127,
-.00048,.00013,
-.00086,.00051,
-.000935,.000353,
-.000983,.000185,
-.001,.000012,
-.000987,-.000162,
-.000943,-.000331,
-.000872,-.00049,
-.00086,-.00051,
-.00048,-.00013,
0.0*
4,1,19,-.00013,.00048,
-.000102,.000487,
-.000073,.000492,
-.000045,.000495,
-.000016,.000497,
.000013,.000497,
.000042,.000496,
.000071,.000492,
.000099,.000487,
.000127,.000481,
.00013,.00048,
.00051,.00086,
.000353,.000935,
.000185,.000983,
.000012,.001,
-.000162,.000987,
-.000331,.000943,
-.00049,.000872,
-.00051,.00086,
-.00013,.00048,
0.0*
%
%ADD13MACRO13*%
%ADD14C,.105*%
%ADD10C,.114*%
%ADD21O,.098X.06*%
%AMMACRO23*
4,1,19,.00048,.00013,
.000487,.000102,
.000492,.000073,
.000495,.000045,
.000497,.000016,
.000497,-.000013,
.000496,-.000042,
.000492,-.000071,
.000487,-.000099,
.000481,-.000127,
.00048,-.00013,
.00086,-.00051,
.000935,-.000353,
.000983,-.000185,
.001,-.000012,
.000987,.000162,
.000943,.000331,
.000872,.00049,
.00086,.00051,
.00048,.00013,
270.*
4,1,19,.00013,-.00048,
.000102,-.000487,
.000073,-.000492,
.000045,-.000495,
.000016,-.000497,
-.000013,-.000497,
-.000042,-.000496,
-.000071,-.000492,
-.000099,-.000487,
-.000127,-.000481,
-.00013,-.00048,
-.00051,-.00086,
-.000353,-.000935,
-.000185,-.000983,
-.000012,-.001,
.000162,-.000987,
.000331,-.000943,
.00049,-.000872,
.00051,-.00086,
.00013,-.00048,
270.*
4,1,19,-.00048,-.00013,
-.000487,-.000102,
-.000492,-.000073,
-.000495,-.000045,
-.000497,-.000016,
-.000497,.000013,
-.000496,.000042,
-.000492,.000071,
-.000487,.000099,
-.000481,.000127,
-.00048,.00013,
-.00086,.00051,
-.000935,.000353,
-.000983,.000185,
-.001,.000012,
-.000987,-.000162,
-.000943,-.000331,
-.000872,-.00049,
-.00086,-.00051,
-.00048,-.00013,
270.*
4,1,19,-.00013,.00048,
-.000102,.000487,
-.000073,.000492,
-.000045,.000495,
-.000016,.000497,
.000013,.000497,
.000042,.000496,
.000071,.000492,
.000099,.000487,
.000127,.000481,
.00013,.00048,
.00051,.00086,
.000353,.000935,
.000185,.000983,
.000012,.001,
-.000162,.000987,
-.000331,.000943,
-.00049,.000872,
-.00051,.00086,
-.00013,.00048,
270.*
%
%ADD23MACRO23*%
%AMMACRO18*
4,1,19,.00048,.00013,
.000487,.000102,
.000492,.000073,
.000495,.000045,
.000497,.000016,
.000497,-.000013,
.000496,-.000042,
.000492,-.000071,
.000487,-.000099,
.000481,-.000127,
.00048,-.00013,
.00086,-.00051,
.000935,-.000353,
.000983,-.000185,
.001,-.000012,
.000987,.000162,
.000943,.000331,
.000872,.00049,
.00086,.00051,
.00048,.00013,
180.*
4,1,19,.00013,-.00048,
.000102,-.000487,
.000073,-.000492,
.000045,-.000495,
.000016,-.000497,
-.000013,-.000497,
-.000042,-.000496,
-.000071,-.000492,
-.000099,-.000487,
-.000127,-.000481,
-.00013,-.00048,
-.00051,-.00086,
-.000353,-.000935,
-.000185,-.000983,
-.000012,-.001,
.000162,-.000987,
.000331,-.000943,
.00049,-.000872,
.00051,-.00086,
.00013,-.00048,
180.*
4,1,19,-.00048,-.00013,
-.000487,-.000102,
-.000492,-.000073,
-.000495,-.000045,
-.000497,-.000016,
-.000497,.000013,
-.000496,.000042,
-.000492,.000071,
-.000487,.000099,
-.000481,.000127,
-.00048,.00013,
-.00086,.00051,
-.000935,.000353,
-.000983,.000185,
-.001,.000012,
-.000987,-.000162,
-.000943,-.000331,
-.000872,-.00049,
-.00086,-.00051,
-.00048,-.00013,
180.*
4,1,19,-.00013,.00048,
-.000102,.000487,
-.000073,.000492,
-.000045,.000495,
-.000016,.000497,
.000013,.000497,
.000042,.000496,
.000071,.000492,
.000099,.000487,
.000127,.000481,
.00013,.00048,
.00051,.00086,
.000353,.000935,
.000185,.000983,
.000012,.001,
-.000162,.000987,
-.000331,.000943,
-.00049,.000872,
-.00051,.00086,
-.00013,.00048,
180.*
%
%ADD18MACRO18*%
%AMMACRO12*
4,1,16,.06891,.04063,
.074918,.028047,
.07865,.014611,
.079993,.000732,
.078905,-.01317,
.075419,-.026672,
.069642,-.039363,
.06891,-.04063,
.07256,-.04427,
.079145,-.030998,
.083325,-.016783,
.084974,-.002059,
.08404,.012728,
.080553,.027128,
.074619,.040704,
.07256,.04427,
.06891,.04063,
0.0*
4,1,16,.04063,-.06891,
.028047,-.074918,
.014611,-.07865,
.000732,-.079993,
-.01317,-.078905,
-.026672,-.075419,
-.039363,-.069642,
-.04063,-.06891,
-.04427,-.07256,
-.030998,-.079145,
-.016783,-.083325,
-.002059,-.084974,
.012728,-.08404,
.027128,-.080553,
.040704,-.074619,
.04427,-.07256,
.04063,-.06891,
0.0*
4,1,16,-.06891,-.04063,
-.074918,-.028047,
-.07865,-.014611,
-.079993,-.000732,
-.078905,.01317,
-.075419,.026672,
-.069642,.039363,
-.06891,.04063,
-.07256,.04427,
-.079145,.030998,
-.083325,.016783,
-.084974,.002059,
-.08404,-.012728,
-.080553,-.027128,
-.074619,-.040704,
-.07256,-.04427,
-.06891,-.04063,
0.0*
4,1,16,-.04063,.06891,
-.028047,.074918,
-.014611,.07865,
-.000732,.079993,
.01317,.078905,
.026672,.075419,
.039363,.069642,
.04063,.06891,
.04427,.07256,
.030998,.079145,
.016783,.083325,
.002059,.084974,
-.012728,.08404,
-.027128,.080553,
-.040704,.074619,
-.04427,.07256,
-.04063,.06891,
0.0*
%
%ADD12MACRO12*%
%AMMACRO11*
4,1,16,.09594,-.02,
.091009,-.036356,
.083314,-.051607,
.073086,-.065291,
.060639,-.07699,
.046348,-.08635,
.030649,-.093086,
.02,-.09594,
.02,-.10104,
.037242,-.096032,
.053352,-.088106,
.067841,-.077503,
.080268,-.064545,
.090257,-.049626,
.097503,-.033199,
.10104,-.02,
.09594,-.02,
0.0*
4,1,16,-.02,-.09594,
-.036356,-.091009,
-.051607,-.083314,
-.065291,-.073086,
-.07699,-.060639,
-.08635,-.046348,
-.093086,-.030649,
-.09594,-.02,
-.10104,-.02,
-.096032,-.037242,
-.088106,-.053352,
-.077503,-.067841,
-.064545,-.080268,
-.049626,-.090257,
-.033199,-.097503,
-.02,-.10104,
-.02,-.09594,
0.0*
4,1,16,-.09594,.02,
-.091009,.036356,
-.083314,.051607,
-.073086,.065291,
-.060639,.07699,
-.046348,.08635,
-.030649,.093086,
-.02,.09594,
-.02,.10104,
-.037242,.096032,
-.053352,.088106,
-.067841,.077503,
-.080268,.064545,
-.090257,.049626,
-.097503,.033199,
-.10104,.02,
-.09594,.02,
0.0*
4,1,16,.02,.09594,
.036356,.091009,
.051607,.083314,
.065291,.073086,
.07699,.060639,
.08635,.046348,
.093086,.030649,
.09594,.02,
.10104,.02,
.096032,.037242,
.088106,.053352,
.077503,.067841,
.064545,.080268,
.049626,.090257,
.033199,.097503,
.02,.10104,
.02,.09594,
0.0*
%
%ADD11MACRO11*%
%ADD27C,.02*%
%ADD28C,.006*%
%ADD31C,.07204*%
%ADD30C,.07704*%
%ADD29C,.11004*%
G75*
%LPD*%
G75*
G36*
G01X-6000Y-6000D02*
X570961D01*
Y262693D01*
X-6000D01*
Y-6000D01*
G37*
%LPC*%
G75*
G36*
G01X3937Y3004D02*
G02X3004Y3937I0J933D01*
G01Y87402D01*
G02X3937Y88335I933J0D01*
G01X192914D01*
G03X197886Y93307I-1J4973D01*
G01Y94240D01*
X269685D01*
G03X276626Y101181I0J6941D01*
G01Y252756D01*
G02X277559Y253689I933J0D01*
G01X561024D01*
G02X561957Y252756I0J-933D01*
G01Y3937D01*
G02X561024Y3004I-933J0D01*
G01X537402D01*
G02X536469Y3937I0J933D01*
G01Y71063D01*
G03X534701Y75691I-6941J0D01*
G02X534732Y76390I373J334D01*
G03X528540Y78574I-2527J2704D01*
G02X528045Y78004I-495J-70D01*
G01X477309D01*
G02X476814Y78574I0J500D01*
G03X469889Y80848I-3665J521D01*
G02X468949Y81085I-440J237D01*
G01Y94488D01*
G03X462008Y101429I-6941J0D01*
G01X379921D01*
G03X372980Y94488I0J-6941D01*
G01Y3937D01*
G02X372047Y3004I-933J0D01*
G01X3937D01*
G37*
%LPD*%
G75*
G36*
G01X510439Y83496D02*
X510440Y83497D01*
X510833Y83104D01*
X510832Y83103D01*
G02X504884Y89073I-2268J3688D01*
G01X504885Y89074D01*
X505278Y88681D01*
X505277Y88680D01*
G03X510439Y83496I3293J-1883D01*
G37*
G36*
G01X506727Y90126D02*
X506726Y90125D01*
X506333Y90518D01*
X506334Y90519D01*
G02X512282Y84549I2268J-3688D01*
G01X512281Y84548D01*
X511888Y84941D01*
X511889Y84942D01*
G03X506727Y90126I-3293J1883D01*
G37*
G36*
G01X498627Y83496D02*
X498628Y83497D01*
X499021Y83104D01*
X499020Y83103D01*
G02X493072Y89073I-2268J3688D01*
G01X493073Y89074D01*
X493466Y88681D01*
X493465Y88680D01*
G03X498627Y83496I3293J-1883D01*
G37*
G36*
G01X494915Y90126D02*
X494914Y90125D01*
X494521Y90518D01*
X494522Y90519D01*
G02X500470Y84549I2268J-3688D01*
G01X500469Y84548D01*
X500076Y84941D01*
X500077Y84942D01*
G03X494915Y90126I-3293J1883D01*
G37*
G36*
G01X399331Y201028D02*
G02Y206452I0J2712D01*
G01X404331D01*
G02Y201028I0J-2712D01*
G01X399331D01*
G37*
G36*
G01Y135280D02*
G02Y140704I0J2712D01*
G01X404331D01*
G02Y135280I0J-2712D01*
G01X399331D01*
G37*
G36*
G01X384331Y201028D02*
G02Y206452I0J2712D01*
G01X389331D01*
G02Y201028I0J-2712D01*
G01X384331D01*
G37*
G36*
G01X377951Y161364D02*
G02X372982Y166334I1J4970D01*
G01Y180114D01*
G02X377952Y185084I4971J-1D01*
G01X484252D01*
G02X489222Y180114I0J-4970D01*
G01Y166334D01*
G02X484252Y161364I-4970J0D01*
G01X377951D01*
G37*
G36*
G01X384331Y135280D02*
G02Y140704I0J2712D01*
G01X389331D01*
G02Y135280I0J-2712D01*
G01X384331D01*
G37*
G36*
G01X329126Y83334D02*
G02X325102I-2012J0D01*
G01Y87335D01*
G02X329126Y87334I2012J-1D01*
G01Y83334D01*
G37*
G36*
G01X329404Y103226D02*
G02Y99204I0J-2011D01*
G01X325403D01*
G02X325404Y103226I1J2011D01*
G01X329404D01*
G37*
G36*
G01X342886Y92311D02*
G02X338862I-2012J0D01*
G01Y96312D01*
G02X342886Y96311I2012J-1D01*
G01Y92311D01*
G37*
G36*
G01X345040Y83447D02*
G02X341016I-2012J0D01*
G01Y87448D01*
G02X345040Y87447I2012J-1D01*
G01Y83447D01*
G37*
G36*
G01X108287Y51816D02*
G02Y57240I0J2712D01*
G01X113287D01*
G02Y51816I0J-2712D01*
G01X108287D01*
G37*
G36*
G01Y7328D02*
G02Y12750I0J2711D01*
G01X113287D01*
G02Y7328I0J-2711D01*
G01X108287D01*
G37*
G36*
G01X93287Y51816D02*
G02Y57240I0J2712D01*
G01X98287D01*
G02Y51816I0J-2712D01*
G01X93287D01*
G37*
G36*
G01X188977Y50246D02*
G02X193946Y45276I-1J-4970D01*
G01Y43307D01*
G02X188977Y38338I-4970J1D01*
G01X82677D01*
G02X77708Y43307I0J4969D01*
G01Y45276D01*
G02X82677Y50246I4970J0D01*
G01X188977D01*
G37*
G36*
G01X98287Y12750D02*
G02Y7328I0J-2711D01*
G01X93287D01*
G02Y12750I0J2711D01*
G01X98287D01*
G37*
G54D31*
X312657Y66142D03*
Y107716D03*
G54D30*
X225097Y15039D03*
Y59528D03*
X516141Y142992D03*
Y208740D03*
G54D29*
X17715Y44095D03*
X525590Y240944D03*
X552795Y40157D03*
G54D26*
X496771Y86811D03*
X508583D03*
G54D16*
X60928Y64173D03*
X73567Y4087D03*
X75100Y36700D03*
X74635Y29153D03*
X76804Y61699D03*
X76600Y68000D03*
X208000Y90000D03*
X204500D03*
X220310Y4087D03*
X218600Y37400D03*
X213100Y83500D03*
X268045Y8270D03*
X258088Y21787D03*
X273551Y37112D03*
X279500Y116900D03*
X279437Y120731D03*
X322100Y26600D03*
X303900Y28900D03*
X313900Y27200D03*
X315166Y52172D03*
X309250Y127439D03*
X322042Y147196D03*
X310500Y184328D03*
X340000Y14667D03*
X324700Y16300D03*
X343028Y87447D03*
X327114Y87334D03*
X340874Y96311D03*
X325404Y101215D03*
X343028Y83447D03*
X327114Y83334D03*
X340874Y92311D03*
X329404Y101215D03*
X336238Y148951D03*
X351040Y34753D03*
X358900Y23928D03*
X506868Y166599D03*
G54D15*
X63713Y48425D03*
X65006Y43434D03*
X60469Y79819D03*
X56667Y83351D03*
X60393Y83934D03*
X52667Y83351D03*
X261719Y52314D03*
X261774Y48506D03*
X261840Y42259D03*
X261924Y38480D03*
X258240Y42259D03*
X258174Y48506D03*
X258119Y52314D03*
X258324Y38480D03*
X286638Y33917D03*
X282148Y51376D03*
X282093Y55184D03*
X278462Y51437D03*
X278407Y55245D03*
X281964Y47752D03*
X278278Y47813D03*
X284292Y61505D03*
X280555Y61542D03*
X299300Y144500D03*
X300000Y164900D03*
X302000Y133500D03*
X301913Y129821D03*
X303000Y144400D03*
X309500Y145000D03*
X303600Y164800D03*
X320332Y160022D03*
X316332D03*
Y164522D03*
X320332D03*
X316332Y155668D03*
X320332D03*
X316438Y151436D03*
X320438D03*
X318500Y193500D03*
X314500D03*
X318500Y188500D03*
X314500D03*
X314454Y213250D03*
X314500Y203500D03*
X318500D03*
Y198500D03*
X314500D03*
X332778Y20000D03*
X328508Y41629D03*
X328424Y45408D03*
X332508Y41629D03*
X332424Y45408D03*
X332565Y49028D03*
X332614Y52663D03*
X328565Y49028D03*
X328614Y52663D03*
X336698Y154738D03*
X340698D03*
X340779Y158381D03*
Y162024D03*
X336779D03*
Y158381D03*
X340779Y165718D03*
X336779D03*
X332000Y183500D03*
X339000Y193500D03*
X335000D03*
Y203500D03*
X339000D03*
Y198500D03*
X335000D03*
X347421Y8568D03*
X350479Y10768D03*
X353229Y52810D03*
X349229D03*
X353095Y45538D03*
X353094Y49157D03*
X352971Y41813D03*
X349095Y45538D03*
X349094Y49157D03*
X348971Y41813D03*
X364750Y37750D03*
X354580Y102351D03*
X350569Y102263D03*
X358824Y108849D03*
X352501Y105640D03*
X350827Y108976D03*
X348696Y105396D03*
X356501Y105640D03*
X354827Y108976D03*
X480101Y230616D03*
X483700Y230522D03*
G54D19*
X137087Y23464D03*
X133937D03*
X130787D03*
X127637D03*
X124487D03*
X137087Y67953D03*
X133937D03*
X130787D03*
X127637D03*
X124487D03*
X428131Y151417D03*
X424981D03*
X421831D03*
X418681D03*
X415531D03*
X428131Y217165D03*
X424981D03*
X421831D03*
X418681D03*
X415531D03*
G54D20*
X225097Y15039D03*
Y59528D03*
X516141Y142992D03*
Y208740D03*
G54D17*
X93287Y10039D03*
Y54528D03*
X113287Y10039D03*
X108287D03*
X98287D03*
X113287Y54528D03*
X108287D03*
X98287D03*
X153287Y10039D03*
X148287D03*
X143287D03*
X153287Y54528D03*
X148287D03*
X143287D03*
X183287Y10039D03*
X178287D03*
X173287D03*
X183287Y54528D03*
X178287D03*
X173287D03*
X208287Y10039D03*
X203287D03*
X193287D03*
X188287D03*
X208287Y54528D03*
X203287D03*
X193287D03*
X188287D03*
X213287Y10039D03*
Y54528D03*
X389331Y137992D03*
X384331D03*
X389331Y203740D03*
X384331D03*
X404331Y137992D03*
X399331D03*
X404331Y203740D03*
X399331D03*
X434331Y137992D03*
Y203740D03*
X444331Y137992D03*
X439331D03*
X444331Y203740D03*
X439331D03*
X479331Y137992D03*
X474331D03*
X469331D03*
X464331D03*
X479331Y203740D03*
X474331D03*
X469331D03*
X464331D03*
X504331Y137992D03*
X499331D03*
X494331D03*
X484331D03*
X504331Y203740D03*
X499331D03*
X494331D03*
X484331D03*
G54D22*
X312657Y66142D03*
Y107716D03*
G54D25*
X484960Y86811D03*
X520394D03*
G54D24*
X473149Y79094D03*
X532205D03*
G54D13*
X5500Y48299D03*
X7960Y85839D03*
X42701Y5500D03*
X48316Y32530D03*
X44316D03*
Y28681D03*
X48316D03*
X44278Y24717D03*
X48278D03*
X49374Y56390D03*
X45374D03*
X45336Y52426D03*
X49336D03*
X41000Y79500D03*
Y75500D03*
X37000Y79500D03*
Y75500D03*
X49374Y60239D03*
X45374D03*
X27960Y85839D03*
X67960D03*
X87960D03*
X107960D03*
X127960D03*
X147960D03*
X167960D03*
X207675Y38907D03*
X204000Y82000D03*
X208000D03*
Y86000D03*
X204000D03*
X187960Y85839D03*
X214906Y39494D03*
X211337Y38963D03*
X222206Y41500D03*
X217880Y83600D03*
X242500Y27000D03*
X246500D03*
X243000Y47500D03*
X247000D03*
X244727Y76591D03*
X244870Y80370D03*
X248866Y76464D03*
X248811Y80272D03*
X281221Y33971D03*
X293146Y81023D03*
X293141Y97997D03*
X284798Y149063D03*
X284905Y160541D03*
X284940Y156881D03*
X284798Y152687D03*
X289800Y165000D03*
X297698Y191563D03*
Y195187D03*
X279122Y174213D03*
Y194213D03*
X297840Y199381D03*
X297805Y203041D03*
X279122Y214213D03*
Y234213D03*
X282142Y251193D03*
X322701Y5500D03*
X321373Y56703D03*
X303734Y89882D03*
X303700Y140700D03*
X315048Y133300D03*
X300754Y205956D03*
X304000Y213000D03*
X322142Y251193D03*
X332666Y27700D03*
X329962Y56703D03*
X326423Y183632D03*
X326000Y217500D03*
X342142Y251193D03*
X357672Y4602D03*
X345690Y20300D03*
X362142Y251193D03*
X382142D03*
X402142D03*
X422142D03*
X442142D03*
X471445Y93346D03*
X476600Y227250D03*
X462142Y251193D03*
X502868Y166448D03*
X502142Y251193D03*
X482142D03*
X519980Y226295D03*
X523642Y226351D03*
X520017Y230070D03*
X523642Y230014D03*
X522142Y251193D03*
X538965Y41992D03*
Y61992D03*
X559461Y68512D03*
Y88512D03*
Y108512D03*
Y148512D03*
Y128512D03*
Y168512D03*
Y188512D03*
Y208512D03*
G54D10*
X-14755Y415558D03*
X-12454Y45507D03*
X17715Y44095D03*
X29461Y718854D03*
X141466Y655356D03*
X395935Y76695D03*
X508569Y15093D03*
X525590Y240944D03*
X552795Y40157D03*
X554126Y315939D03*
Y685624D03*
G54D14*
X68112Y15039D03*
Y59528D03*
X233462Y15039D03*
Y59528D03*
X359156Y142992D03*
Y208740D03*
X524506Y142992D03*
Y208740D03*
G54D21*
X295472Y65571D03*
Y108287D03*
X330590Y65571D03*
Y108287D03*
G54D18*
X88287Y10039D03*
Y54528D03*
X118287Y10039D03*
X103287D03*
X118287Y54528D03*
X103287D03*
X140237Y23464D03*
X121337D03*
X140237Y67953D03*
X121337D03*
X163287Y10039D03*
X158287D03*
X163287Y54528D03*
X158287D03*
X168287Y10039D03*
Y54528D03*
X198287Y10039D03*
Y54528D03*
X313617Y81023D03*
X321440Y101571D03*
X337406Y79575D03*
X341133Y80298D03*
X326892Y79371D03*
X338145Y98740D03*
X337670Y90976D03*
X332822Y103140D03*
X327057Y90943D03*
X345642Y90134D03*
X379331Y137992D03*
Y203740D03*
X409331Y137992D03*
X394331D03*
X412381Y151417D03*
Y217165D03*
X409331Y203740D03*
X394331D03*
X431281Y151417D03*
Y217165D03*
X459331Y137992D03*
X454331D03*
X449331D03*
X459331Y203740D03*
X454331D03*
X449331D03*
X489331Y137992D03*
Y203740D03*
G54D23*
X308208Y101945D03*
G54D12*
X15748Y67008D03*
X303150Y13780D03*
Y242913D03*
X551181Y13780D03*
G54D11*
X15748Y15827D03*
X551181Y242913D03*
%LPC*%
G75*
G54D27*
G01X-139981Y-146685D02*
G02I-12000J0D01*
G01X-145131D02*
G02I-6850J0D01*
G01X-135981D02*
X-167981D01*
G01X-135981Y-162685D02*
Y-242685D01*
G01D02*
X971619D01*
G01X-135981Y-198185D02*
X971619D01*
G01X-151981Y-162685D02*
Y-130685D01*
G01X-135981Y-162685D02*
X971619D01*
G01X184119D02*
Y-242685D01*
G01X321619Y-162685D02*
Y-242685D01*
G01X436619Y-162685D02*
Y-242685D01*
G01X604119Y-162685D02*
Y-242685D01*
G01X774119Y-162685D02*
Y-242685D01*
G01X971619Y-162685D02*
Y-242685D01*
G01X999619Y-146685D02*
G02I-12000J0D01*
G01X1003619D02*
X971619D01*
G01X994469D02*
G02I-6850J0D01*
G01X987619Y-162685D02*
Y-130685D01*
G54D28*
G01X-116181Y-215185D02*
Y-232685D01*
G01X-121203Y-215185D02*
X-111159D01*
G01X-103048Y-232685D02*
Y-215185D01*
X-97808D01*
X-96061Y-216060D01*
X-94751Y-218102D01*
X-94314Y-220435D01*
X-94751Y-222768D01*
X-95843Y-224518D01*
X-97808Y-225394D01*
X-103048D01*
G01X-58878Y-216644D02*
X-60188Y-215768D01*
X-61716Y-215185D01*
X-63463D01*
X-65428Y-216060D01*
X-66956Y-217518D01*
X-68048Y-219269D01*
X-68921Y-222185D01*
X-69140Y-224810D01*
X-68703Y-227435D01*
X-68048Y-229185D01*
X-66738Y-230935D01*
X-65209Y-232102D01*
X-63681Y-232685D01*
X-62153D01*
X-60624Y-232102D01*
X-59314Y-231227D01*
X-58222Y-230061D01*
G01X-49893Y-232685D02*
Y-215185D01*
G01Y-223643D02*
X-48801Y-222185D01*
X-47709Y-221310D01*
X-45963Y-221019D01*
X-44653Y-221310D01*
X-43124Y-222477D01*
X-42469Y-224227D01*
Y-232685D01*
G01X-24751D02*
Y-221019D01*
G01Y-223060D02*
X-25624Y-221894D01*
X-26935Y-221310D01*
X-28463Y-221019D01*
X-29991Y-221602D01*
X-31301Y-222768D01*
X-32175Y-224518D01*
X-32611Y-226852D01*
X-32175Y-229185D01*
X-31301Y-230935D01*
X-29991Y-232102D01*
X-28463Y-232685D01*
X-26935Y-232393D01*
X-25624Y-231519D01*
X-24751Y-230352D01*
G01X-14893Y-232685D02*
Y-221019D01*
G01Y-223935D02*
X-14019Y-222477D01*
X-12709Y-221310D01*
X-10963Y-221019D01*
X-9435Y-221310D01*
X-8124Y-222477D01*
X-7469Y-224518D01*
Y-232685D01*
G01X2607D02*
Y-221019D01*
G01Y-223935D02*
X3481Y-222477D01*
X4791Y-221310D01*
X6537Y-221019D01*
X8065Y-221310D01*
X9376Y-222477D01*
X10031Y-224518D01*
Y-232685D01*
G01X20544Y-224810D02*
X27531D01*
X26876Y-222768D01*
X25784Y-221602D01*
X24256Y-221019D01*
X22727Y-221310D01*
X21417Y-222185D01*
X20544Y-224227D01*
X20107Y-225977D01*
Y-227727D01*
X20544Y-229477D01*
X21636Y-231227D01*
X22946Y-232393D01*
X24474Y-232685D01*
X26002Y-232102D01*
X27531Y-230352D01*
G01X41319Y-232685D02*
Y-215185D01*
G01X71734Y-232685D02*
Y-215185D01*
G01X80904D02*
Y-232685D01*
G01Y-223935D02*
X71734D01*
G01X89016Y-232685D02*
Y-215185D01*
X93382D01*
X95129Y-216060D01*
X96439Y-217227D01*
X97531Y-218976D01*
X98404Y-221019D01*
X98622Y-223935D01*
X98404Y-226852D01*
X97531Y-228894D01*
X96439Y-230644D01*
X95129Y-231810D01*
X93382Y-232685D01*
X89016D01*
G01X106516D02*
Y-215185D01*
X110882D01*
X112629Y-216060D01*
X113939Y-217227D01*
X115031Y-218976D01*
X115904Y-221019D01*
X116122Y-223935D01*
X115904Y-226852D01*
X115031Y-228894D01*
X113939Y-230644D01*
X112629Y-231810D01*
X110882Y-232685D01*
X106516D01*
G01X148065Y-223352D02*
X148939Y-222477D01*
X149594Y-221019D01*
X150031Y-218976D01*
X149594Y-217227D01*
X148721Y-216060D01*
X147192Y-215185D01*
X141297D01*
Y-232685D01*
X148502D01*
X150031Y-231519D01*
X150904Y-229768D01*
X151341Y-227727D01*
X150904Y-225685D01*
X149594Y-223935D01*
X148065Y-223352D01*
X141297D01*
G01X159452Y-232685D02*
Y-215185D01*
X164692D01*
X166439Y-216060D01*
X167749Y-218102D01*
X168186Y-220435D01*
X167749Y-222768D01*
X166657Y-224518D01*
X164692Y-225394D01*
X159452D01*
G01X-16858Y-187685D02*
Y-170185D01*
X-11181Y-184768D01*
X-5504Y-170185D01*
Y-187685D01*
G01X6319D02*
X5009Y-187393D01*
X3699Y-186227D01*
X2825Y-184185D01*
X2389Y-181852D01*
X2825Y-179518D01*
X3699Y-177477D01*
X5009Y-176310D01*
X6319Y-176019D01*
X7629Y-176310D01*
X8939Y-177477D01*
X9812Y-179518D01*
X10031Y-181852D01*
X9812Y-184185D01*
X8939Y-186227D01*
X7629Y-187393D01*
X6319Y-187685D01*
G01X27749Y-170185D02*
Y-187685D01*
G01Y-185061D02*
X26876Y-186519D01*
X25565Y-187393D01*
X24037Y-187685D01*
X22291Y-187102D01*
X20981Y-185644D01*
X20107Y-183894D01*
X19889Y-181852D01*
X20107Y-179810D01*
X20981Y-178060D01*
X22291Y-176602D01*
X24037Y-176019D01*
X25565Y-176310D01*
X26657Y-176894D01*
X27749Y-178060D01*
G01X38044Y-179810D02*
X45031D01*
X44376Y-177768D01*
X43284Y-176602D01*
X41756Y-176019D01*
X40227Y-176310D01*
X38917Y-177185D01*
X38044Y-179227D01*
X37607Y-180977D01*
Y-182727D01*
X38044Y-184477D01*
X39136Y-186227D01*
X40446Y-187393D01*
X41974Y-187685D01*
X43502Y-187102D01*
X45031Y-185352D01*
G01X58819Y-187685D02*
Y-170185D01*
G01X204702Y-187685D02*
Y-170185D01*
X209942D01*
X211689Y-171060D01*
X212999Y-173102D01*
X213436Y-175435D01*
X212999Y-177768D01*
X211907Y-179518D01*
X209942Y-180394D01*
X204702D01*
G01X231372Y-171644D02*
X230062Y-170768D01*
X228534Y-170185D01*
X226787D01*
X224822Y-171060D01*
X223294Y-172518D01*
X222202Y-174269D01*
X221329Y-177185D01*
X221110Y-179810D01*
X221547Y-182435D01*
X222202Y-184185D01*
X223512Y-185935D01*
X225041Y-187102D01*
X226569Y-187685D01*
X228097D01*
X229626Y-187102D01*
X230936Y-186227D01*
X232028Y-185061D01*
G01X245815Y-178352D02*
X246689Y-177477D01*
X247344Y-176019D01*
X247781Y-173976D01*
X247344Y-172227D01*
X246471Y-171060D01*
X244942Y-170185D01*
X239047D01*
Y-187685D01*
X246252D01*
X247781Y-186519D01*
X248654Y-184768D01*
X249091Y-182727D01*
X248654Y-180685D01*
X247344Y-178935D01*
X245815Y-178352D01*
X239047D01*
G01X255019Y-193518D02*
X268119D01*
G01X274047Y-187685D02*
Y-170185D01*
X284091Y-187685D01*
Y-170185D01*
G01X296569Y-187685D02*
X294822Y-187393D01*
X293294Y-186227D01*
X291984Y-184477D01*
X291110Y-182435D01*
X290674Y-180102D01*
Y-177768D01*
X291110Y-175435D01*
X291984Y-173393D01*
X293294Y-171644D01*
X294822Y-170477D01*
X296569Y-170185D01*
X298315Y-170477D01*
X299844Y-171644D01*
X301154Y-173393D01*
X302028Y-175435D01*
X302464Y-177768D01*
Y-180102D01*
X302028Y-182435D01*
X301154Y-184477D01*
X299844Y-186227D01*
X298315Y-187393D01*
X296569Y-187685D01*
G01X217819Y-232685D02*
Y-215185D01*
X215199Y-218685D01*
G01Y-232685D02*
X220439D01*
G01X234882D02*
X235319Y-228894D01*
X235974Y-225685D01*
X236847Y-222768D01*
X237939Y-219560D01*
X239686Y-215185D01*
X230952D01*
G01X248016Y-229185D02*
X249325Y-231227D01*
X251072Y-232393D01*
X253037Y-232685D01*
X254784Y-232393D01*
X256531Y-230935D01*
X257622Y-229185D01*
X257841Y-227435D01*
X257404Y-225394D01*
X255876Y-223935D01*
X254347Y-223352D01*
X252382D01*
G01X254347D02*
X255657Y-222477D01*
X256749Y-221019D01*
X257186Y-219269D01*
X256749Y-217518D01*
X255657Y-216060D01*
X253692Y-215185D01*
X251727Y-215477D01*
X249762Y-216644D01*
G01X270319Y-215185D02*
X268572Y-215768D01*
X267262Y-217227D01*
X266389Y-218976D01*
X265734Y-221310D01*
X265516Y-223935D01*
X265734Y-226560D01*
X266389Y-228894D01*
X267262Y-230644D01*
X268572Y-232102D01*
X270319Y-232685D01*
X272065Y-232102D01*
X273376Y-230644D01*
X274249Y-228894D01*
X274904Y-226560D01*
X275122Y-223935D01*
X274904Y-221310D01*
X274249Y-218976D01*
X273376Y-217227D01*
X272065Y-215768D01*
X270319Y-215185D01*
G01X287819Y-232685D02*
Y-215185D01*
X285199Y-218685D01*
G01Y-232685D02*
X290439D01*
G01X365784Y-230352D02*
X367531Y-231810D01*
X369496Y-232685D01*
X371242D01*
X372989Y-231810D01*
X374299Y-230352D01*
X374954Y-228310D01*
X374517Y-226269D01*
X373426Y-224518D01*
X371461Y-223352D01*
X368841Y-222768D01*
X367312Y-221602D01*
X366657Y-219560D01*
X367094Y-217518D01*
X368186Y-216060D01*
X369714Y-215185D01*
X371242D01*
X372771Y-215768D01*
X374081Y-217227D01*
G01X382410Y-232685D02*
X387869Y-215185D01*
X393328Y-232685D01*
G01X391362Y-226560D02*
X384375D01*
G01X347410Y-170185D02*
X352869Y-187685D01*
X358328Y-170185D01*
G01X374736Y-187685D02*
X366002D01*
Y-170185D01*
X374736D01*
G01X371242Y-178643D02*
X366002D01*
G01X383502Y-187685D02*
Y-170185D01*
X388961D01*
X390707Y-171060D01*
X391799Y-172227D01*
X392236Y-174560D01*
X391799Y-176894D01*
X390489Y-178352D01*
X388961Y-179227D01*
X383502D01*
G01X388961D02*
X392236Y-187685D01*
G01X405369Y-188268D02*
X404932Y-187977D01*
Y-187393D01*
X405369Y-187102D01*
X405806Y-187393D01*
Y-187977D01*
X405369Y-188268D01*
G01X480952Y-215185D02*
Y-232685D01*
X489686D01*
G01X498671Y-218102D02*
X499981Y-216352D01*
X501509Y-215477D01*
X503256Y-215185D01*
X505439Y-215768D01*
X506967Y-217227D01*
X507404Y-218976D01*
X507186Y-220727D01*
X506312Y-222185D01*
X501946Y-225102D01*
X499981Y-227143D01*
X498671Y-230061D01*
X498234Y-232685D01*
X507404D01*
G01X521629Y-223935D02*
X525996D01*
Y-229185D01*
X524686Y-230935D01*
X523157Y-232102D01*
X520974Y-232685D01*
X518791Y-232102D01*
X517262Y-230935D01*
X515952Y-229185D01*
X515079Y-227143D01*
X514642Y-224810D01*
Y-222768D01*
X515079Y-221019D01*
X515952Y-218976D01*
X517262Y-217227D01*
X518572Y-216060D01*
X520319Y-215185D01*
X521847D01*
X523594Y-215768D01*
X524904Y-216935D01*
G01X532797Y-232685D02*
Y-215185D01*
X542841Y-232685D01*
Y-215185D01*
G01X550516Y-232685D02*
Y-215185D01*
X554882D01*
X556629Y-216060D01*
X557939Y-217227D01*
X559031Y-218976D01*
X559904Y-221019D01*
X560122Y-223935D01*
X559904Y-226852D01*
X559031Y-228894D01*
X557939Y-230644D01*
X556629Y-231810D01*
X554882Y-232685D01*
X550516D01*
G01X480952Y-170185D02*
Y-187685D01*
X489686D01*
G01X506749D02*
Y-176019D01*
G01Y-178060D02*
X505876Y-176894D01*
X504565Y-176310D01*
X503037Y-176019D01*
X501509Y-176602D01*
X500199Y-177768D01*
X499325Y-179518D01*
X498889Y-181852D01*
X499325Y-184185D01*
X500199Y-185935D01*
X501509Y-187102D01*
X503037Y-187685D01*
X504565Y-187393D01*
X505876Y-186519D01*
X506749Y-185352D01*
G01X515734Y-192935D02*
X517044Y-193518D01*
X518791Y-192935D01*
X519882Y-191769D01*
X520756Y-190310D01*
X522065Y-185644D01*
X524904Y-176019D01*
G01X517917D02*
X522065Y-185644D01*
G01X534544Y-179810D02*
X541531D01*
X540876Y-177768D01*
X539784Y-176602D01*
X538256Y-176019D01*
X536727Y-176310D01*
X535417Y-177185D01*
X534544Y-179227D01*
X534107Y-180977D01*
Y-182727D01*
X534544Y-184477D01*
X535636Y-186227D01*
X536946Y-187393D01*
X538474Y-187685D01*
X540002Y-187102D01*
X541531Y-185352D01*
G01X552262Y-187685D02*
Y-176019D01*
G01Y-178352D02*
X553354Y-177185D01*
X554446Y-176310D01*
X555974Y-176019D01*
X557065Y-176310D01*
X558376Y-177185D01*
G01X623066Y-187685D02*
Y-170185D01*
X627432D01*
X629179Y-171060D01*
X630489Y-172227D01*
X631581Y-173976D01*
X632454Y-176019D01*
X632672Y-178935D01*
X632454Y-181852D01*
X631581Y-183894D01*
X630489Y-185644D01*
X629179Y-186810D01*
X627432Y-187685D01*
X623066D01*
G01X642094Y-179810D02*
X649081D01*
X648426Y-177768D01*
X647334Y-176602D01*
X645806Y-176019D01*
X644277Y-176310D01*
X642967Y-177185D01*
X642094Y-179227D01*
X641657Y-180977D01*
Y-182727D01*
X642094Y-184477D01*
X643186Y-186227D01*
X644496Y-187393D01*
X646024Y-187685D01*
X647552Y-187102D01*
X649081Y-185352D01*
G01X659594Y-185644D02*
X660686Y-186810D01*
X662214Y-187685D01*
X663524D01*
X664834Y-187102D01*
X665707Y-186227D01*
X666144Y-185061D01*
X665926Y-183310D01*
X665052Y-182435D01*
X661122Y-180685D01*
X660249Y-178643D01*
X660686Y-177185D01*
X661559Y-176310D01*
X662869Y-176019D01*
X664179Y-176310D01*
X665489Y-177185D01*
G01X680369Y-176019D02*
Y-187685D01*
G01Y-171352D02*
X679932Y-171060D01*
Y-170477D01*
X680369Y-170185D01*
X680806Y-170477D01*
Y-171060D01*
X680369Y-171352D01*
G01X694812Y-192060D02*
X696341Y-193227D01*
X698087Y-193518D01*
X699615Y-193227D01*
X700926Y-191769D01*
X701799Y-189727D01*
Y-176019D01*
G01Y-178352D02*
X700926Y-177185D01*
X699615Y-176310D01*
X698087Y-176019D01*
X696341Y-176602D01*
X695249Y-177768D01*
X694375Y-179810D01*
X693939Y-181852D01*
X694157Y-183602D01*
X695031Y-185644D01*
X696341Y-187102D01*
X698087Y-187685D01*
X699397Y-187393D01*
X700926Y-186227D01*
X701799Y-185061D01*
G01X711657Y-187685D02*
Y-176019D01*
G01Y-178935D02*
X712531Y-177477D01*
X713841Y-176310D01*
X715587Y-176019D01*
X717115Y-176310D01*
X718426Y-177477D01*
X719081Y-179518D01*
Y-187685D01*
G01X729594Y-179810D02*
X736581D01*
X735926Y-177768D01*
X734834Y-176602D01*
X733306Y-176019D01*
X731777Y-176310D01*
X730467Y-177185D01*
X729594Y-179227D01*
X729157Y-180977D01*
Y-182727D01*
X729594Y-184477D01*
X730686Y-186227D01*
X731996Y-187393D01*
X733524Y-187685D01*
X735052Y-187102D01*
X736581Y-185352D01*
G01X747312Y-187685D02*
Y-176019D01*
G01Y-178352D02*
X748404Y-177185D01*
X749496Y-176310D01*
X751024Y-176019D01*
X752115Y-176310D01*
X753426Y-177185D01*
G01X664179Y-223935D02*
X668546D01*
Y-229185D01*
X667236Y-230935D01*
X665707Y-232102D01*
X663524Y-232685D01*
X661341Y-232102D01*
X659812Y-230935D01*
X658502Y-229185D01*
X657629Y-227143D01*
X657192Y-224810D01*
Y-222768D01*
X657629Y-221019D01*
X658502Y-218976D01*
X659812Y-217227D01*
X661122Y-216060D01*
X662869Y-215185D01*
X664397D01*
X666144Y-215768D01*
X667454Y-216935D01*
G01X684736Y-232685D02*
X676002D01*
Y-215185D01*
X684736D01*
G01X681242Y-223643D02*
X676002D01*
G01X693502Y-215185D02*
Y-232685D01*
X702236D01*
G01X715369D02*
X713622Y-232393D01*
X712094Y-231227D01*
X710784Y-229477D01*
X709910Y-227435D01*
X709474Y-225102D01*
Y-222768D01*
X709910Y-220435D01*
X710784Y-218393D01*
X712094Y-216644D01*
X713622Y-215477D01*
X715369Y-215185D01*
X717115Y-215477D01*
X718644Y-216644D01*
X719954Y-218393D01*
X720828Y-220435D01*
X721264Y-222768D01*
Y-225102D01*
X720828Y-227435D01*
X719954Y-229477D01*
X718644Y-231227D01*
X717115Y-232393D01*
X715369Y-232685D01*
G01X794069Y-215185D02*
X792322Y-215768D01*
X791012Y-217227D01*
X790139Y-218976D01*
X789484Y-221310D01*
X789266Y-223935D01*
X789484Y-226560D01*
X790139Y-228894D01*
X791012Y-230644D01*
X792322Y-232102D01*
X794069Y-232685D01*
X795815Y-232102D01*
X797126Y-230644D01*
X797999Y-228894D01*
X798654Y-226560D01*
X798872Y-223935D01*
X798654Y-221310D01*
X797999Y-218976D01*
X797126Y-217227D01*
X795815Y-215768D01*
X794069Y-215185D01*
G01X807421Y-225394D02*
X808949Y-223352D01*
X810259Y-222185D01*
X812006Y-221602D01*
X813534Y-222185D01*
X814626Y-223352D01*
X815499Y-225102D01*
X815717Y-227143D01*
X815499Y-228894D01*
X814626Y-230644D01*
X813315Y-232102D01*
X811787Y-232685D01*
X810041Y-232102D01*
X808512Y-230352D01*
X807639Y-227727D01*
X807421Y-224810D01*
X807857Y-221019D01*
X808512Y-218976D01*
X809604Y-216935D01*
X811132Y-215477D01*
X812661Y-215185D01*
X814189Y-215768D01*
X815281Y-217227D01*
G01X825139Y-233268D02*
X832999Y-215185D01*
G01X842421Y-218102D02*
X843731Y-216352D01*
X845259Y-215477D01*
X847006Y-215185D01*
X849189Y-215768D01*
X850717Y-217227D01*
X851154Y-218976D01*
X850936Y-220727D01*
X850062Y-222185D01*
X845696Y-225102D01*
X843731Y-227143D01*
X842421Y-230061D01*
X841984Y-232685D01*
X851154D01*
G01X859921Y-218102D02*
X861231Y-216352D01*
X862759Y-215477D01*
X864506Y-215185D01*
X866689Y-215768D01*
X868217Y-217227D01*
X868654Y-218976D01*
X868436Y-220727D01*
X867562Y-222185D01*
X863196Y-225102D01*
X861231Y-227143D01*
X859921Y-230061D01*
X859484Y-232685D01*
X868654D01*
G01X877639Y-233268D02*
X885499Y-215185D01*
G01X894921Y-218102D02*
X896231Y-216352D01*
X897759Y-215477D01*
X899506Y-215185D01*
X901689Y-215768D01*
X903217Y-217227D01*
X903654Y-218976D01*
X903436Y-220727D01*
X902562Y-222185D01*
X898196Y-225102D01*
X896231Y-227143D01*
X894921Y-230061D01*
X894484Y-232685D01*
X903654D01*
G01X916569Y-215185D02*
X914822Y-215768D01*
X913512Y-217227D01*
X912639Y-218976D01*
X911984Y-221310D01*
X911766Y-223935D01*
X911984Y-226560D01*
X912639Y-228894D01*
X913512Y-230644D01*
X914822Y-232102D01*
X916569Y-232685D01*
X918315Y-232102D01*
X919626Y-230644D01*
X920499Y-228894D01*
X921154Y-226560D01*
X921372Y-223935D01*
X921154Y-221310D01*
X920499Y-218976D01*
X919626Y-217227D01*
X918315Y-215768D01*
X916569Y-215185D01*
G01X934069Y-232685D02*
Y-215185D01*
X931449Y-218685D01*
G01Y-232685D02*
X936689D01*
G01X951132D02*
X951569Y-228894D01*
X952224Y-225685D01*
X953097Y-222768D01*
X954189Y-219560D01*
X955936Y-215185D01*
X947202D01*
G01X841766Y-187685D02*
Y-170185D01*
X846132D01*
X847879Y-171060D01*
X849189Y-172227D01*
X850281Y-173976D01*
X851154Y-176019D01*
X851372Y-178935D01*
X851154Y-181852D01*
X850281Y-183894D01*
X849189Y-185644D01*
X847879Y-186810D01*
X846132Y-187685D01*
X841766D01*
G01X867999D02*
Y-176019D01*
G01Y-178060D02*
X867126Y-176894D01*
X865815Y-176310D01*
X864287Y-176019D01*
X862759Y-176602D01*
X861449Y-177768D01*
X860575Y-179518D01*
X860139Y-181852D01*
X860575Y-184185D01*
X861449Y-185935D01*
X862759Y-187102D01*
X864287Y-187685D01*
X865815Y-187393D01*
X867126Y-186519D01*
X867999Y-185352D01*
G01X881569Y-170185D02*
Y-187685D01*
G01X878512Y-176019D02*
X884626D01*
G01X895794Y-179810D02*
X902781D01*
X902126Y-177768D01*
X901034Y-176602D01*
X899506Y-176019D01*
X897977Y-176310D01*
X896667Y-177185D01*
X895794Y-179227D01*
X895357Y-180977D01*
Y-182727D01*
X895794Y-184477D01*
X896886Y-186227D01*
X898196Y-187393D01*
X899724Y-187685D01*
X901252Y-187102D01*
X902781Y-185352D01*
M02*
